# BASEBOARD_FAB2 (Tioga Pass) — schematic netlist excerpt (pin names and nets, part order shuffled) for the footprints in the layout excerpt that follows; sources: Cadence DE-HDL packaged netlist, KiCad conversion of Wiwynn_Tioga_Pass_MB.brd

R7M3  RES  10.0 1% CHIP  pkg 0402  page 99 : A = SMB_DDR_KLM_SCL_G_R ; B = SMB_DDR_KLM_SCL_G
C2T15  CAP_A  0.1UF 16V 10% X7R  pkg 0402V  page 185 : A = P3V3 ; B = GND
C5G52  CAP_A  22.0UF 4V 20% X6S  pkg 0603V  page 242 : A = PVDDQ_ABC ; B = GND

(kicad_pcb
	(version 20260206)
	(generator "pcbnew")
	(generator_version "10.0")
	(general
		(thickness 1.6)
		(legacy_teardrops no)
	)
	(paper "A4")
	(title_block
		(title "Wiwynn_Tioga_Pass_MB.brd")
		(comment 1 "Tioga Pass / footprints 2855-2857 of 4770")
	)
	(layers
		(0 "F.Cu" signal "TOP")
		(4 "In1.Cu" signal "L2GND")
		(6 "In2.Cu" signal "L3")
		(8 "In3.Cu" signal "L4GND")
		(10 "In4.Cu" signal "L5")
		(12 "In5.Cu" signal "L6GND")
		(14 "In6.Cu" signal "L7VCC")
		(16 "In7.Cu" signal "L8VCC")
		(18 "In8.Cu" signal "L9GND")
		(20 "In9.Cu" signal "L10")
		(22 "In10.Cu" signal "L11GND")
		(24 "In11.Cu" signal "L12")
		(26 "In12.Cu" signal "L13GND")
		(2 "B.Cu" signal "BOTTOM")
		(9 "F.Adhes" user "F.Adhesive")
		(11 "B.Adhes" user "B.Adhesive")
		(13 "F.Paste" user "Package Geometry/Pastemask Top")
		(15 "B.Paste" user "Package Geometry/Pastemask Bottom")
		(5 "F.SilkS" user "Ref Des/Silkscreen Top")
		(7 "B.SilkS" user "Ref Des/Silkscreen Bottom")
		(1 "F.Mask" user "Board Geometry/Soldermask Top")
		(3 "B.Mask" user "Board Geometry/Soldermask Bottom")
		(17 "Dwgs.User" user "User.Drawings")
		(19 "Cmts.User" user "User.Comments")
		(21 "Eco1.User" user "User.Eco1")
		(23 "Eco2.User" user "User.Eco2")
		(25 "Edge.Cuts" user "Board Geometry/Outline")
		(27 "Margin" user)
		(31 "F.CrtYd" user "Package Geometry/Place Bound Top")
		(29 "B.CrtYd" user "Package Geometry/Place Bound Bottom")
		(35 "F.Fab" user "Ref Des/Assembly Top")
		(33 "B.Fab" user "Ref Des/Assembly Bottom")
	)
	(footprint ""
		(layer "B.Cu")
		(at 390.635744 -25.794716 -90)
		(property "Reference" "C2T15"
			(at 0 0 90)
			(layer "B.SilkS")
			(hide yes)
			(effects
				(font
					(size 1.27 1.27)
				)
				(justify mirror)
			)
		)
		(property "Value" ""
			(at 0 0 90)
			(layer "B.Fab")
			(effects
				(font
					(size 1.27 1.27)
				)
				(justify mirror)
			)
		)
		(duplicate_pad_numbers_are_jumpers no)
		(fp_poly
			(pts
				(xy -0.3048 -0.1016) (xy -0.3048 0.9906) (xy 0.3048 0.9906) (xy 0.3048 -0.1016)
			)
			(stroke
				(width 0)
				(type default)
			)
			(fill no)
			(layer "B.CrtYd")
		)
		(fp_line
			(start -0.3048 0.9906)
			(end -0.3048 -0.1016)
			(stroke
				(width 0.1)
				(type default)
			)
			(layer "B.Fab")
		)
		(fp_line
			(start 0.3048 0.9906)
			(end -0.3048 0.9906)
			(stroke
				(width 0.1)
				(type default)
			)
			(layer "B.Fab")
		)
		(fp_line
			(start -0.3048 -0.1016)
			(end 0.3048 -0.1016)
			(stroke
				(width 0.1)
				(type default)
			)
			(layer "B.Fab")
		)
		(fp_line
			(start 0.3048 -0.1016)
			(end 0.3048 0.9906)
			(stroke
				(width 0.1)
				(type default)
			)
			(layer "B.Fab")
		)
		(pad "1" smd rect
			(at 0 0 90)
			(size 0.508 0.508)
			(layers "B.Cu" "B.Mask" "B.Paste")
			(net "P3V3")
		)
		(pad "2" smd rect
			(at 0 0.889 90)
			(size 0.508 0.508)
			(layers "B.Cu" "B.Mask" "B.Paste")
			(net "GND")
		)
		(zone
			(layer "B.Cu")
			(hatch none 0.5)
			(connect_pads
				(clearance 0)
			)
			(min_thickness 0.25)
			(keepout
				(tracks not_allowed)
				(vias allowed)
				(pads allowed)
				(copperpour not_allowed)
				(footprints allowed)
			)
			(placement
				(enabled no)
				(sheetname "")
			)
			(fill
				(thermal_gap 0.5)
				(thermal_bridge_width 0.5)
				(island_removal_mode 0)
			)
			(polygon
				(pts
					(xy 390.000744 -25.540716) (xy 390.000744 -26.048716) (xy 390.381744 -26.048716) (xy 390.381744 -25.540716)
				)
			)
		)
		(zone
			(layer "B.Cu")
			(hatch none 0.5)
			(connect_pads
				(clearance 0)
			)
			(min_thickness 0.25)
			(keepout
				(tracks allowed)
				(vias not_allowed)
				(pads allowed)
				(copperpour not_allowed)
				(footprints allowed)
			)
			(placement
				(enabled no)
				(sheetname "")
			)
			(fill
				(thermal_gap 0.5)
				(thermal_bridge_width 0.5)
				(island_removal_mode 0)
			)
			(polygon
				(pts
					(xy 390.381744 -25.540716) (xy 390.381744 -26.048716) (xy 390.000744 -26.048716) (xy 390.000744 -25.540716)
				)
			)
		)
	)
	(footprint ""
		(layer "B.Cu")
		(at 156.06522 -124.0917)
		(property "Reference" "R7M3"
			(at 0 0 0)
			(layer "B.SilkS")
			(hide yes)
			(effects
				(font
					(size 1.27 1.27)
				)
				(justify mirror)
			)
		)
		(property "Value" ""
			(at 0 0 0)
			(layer "B.Fab")
			(effects
				(font
					(size 1.27 1.27)
				)
				(justify mirror)
			)
		)
		(duplicate_pad_numbers_are_jumpers no)
		(fp_poly
			(pts
				(xy 0.2794 -0.1016) (xy -0.2794 -0.1016) (xy -0.2794 0.9906) (xy 0.2794 0.9906)
			)
			(stroke
				(width 0)
				(type default)
			)
			(fill no)
			(layer "B.CrtYd")
		)
		(fp_line
			(start -0.2794 -0.1016)
			(end 0.2794 -0.1016)
			(stroke
				(width 0.1)
				(type default)
			)
			(layer "B.Fab")
		)
		(fp_line
			(start -0.2794 0.9906)
			(end -0.2794 -0.1016)
			(stroke
				(width 0.1)
				(type default)
			)
			(layer "B.Fab")
		)
		(fp_line
			(start 0.2794 -0.1016)
			(end 0.2794 0.9906)
			(stroke
				(width 0.1)
				(type default)
			)
			(layer "B.Fab")
		)
		(fp_line
			(start 0.2794 0.9906)
			(end -0.2794 0.9906)
			(stroke
				(width 0.1)
				(type default)
			)
			(layer "B.Fab")
		)
		(pad "1" smd rect
			(at 0 0 180)
			(size 0.508 0.508)
			(layers "B.Cu" "B.Mask" "B.Paste")
			(net "SMB_DDR_KLM_SCL_G_R")
		)
		(pad "2" smd rect
			(at 0 0.889 180)
			(size 0.508 0.508)
			(layers "B.Cu" "B.Mask" "B.Paste")
			(net "SMB_DDR_KLM_SCL_G")
		)
		(zone
			(layer "B.Cu")
			(hatch none 0.5)
			(connect_pads
				(clearance 0)
			)
			(min_thickness 0.25)
			(keepout
				(tracks allowed)
				(vias not_allowed)
				(pads allowed)
				(copperpour not_allowed)
				(footprints allowed)
			)
			(placement
				(enabled no)
				(sheetname "")
			)
			(fill
				(thermal_gap 0.5)
				(thermal_bridge_width 0.5)
				(island_removal_mode 0)
			)
			(polygon
				(pts
					(xy 156.31922 -123.8377) (xy 155.81122 -123.8377) (xy 155.81122 -123.4567) (xy 156.31922 -123.4567)
				)
			)
		)
		(zone
			(layer "B.Cu")
			(hatch none 0.5)
			(connect_pads
				(clearance 0)
			)
			(min_thickness 0.25)
			(keepout
				(tracks not_allowed)
				(vias allowed)
				(pads allowed)
				(copperpour not_allowed)
				(footprints allowed)
			)
			(placement
				(enabled no)
				(sheetname "")
			)
			(fill
				(thermal_gap 0.5)
				(thermal_bridge_width 0.5)
				(island_removal_mode 0)
			)
			(polygon
				(pts
					(xy 156.31922 -123.4567) (xy 155.81122 -123.4567) (xy 155.81122 -123.8377) (xy 156.31922 -123.8377)
				)
			)
		)
	)
	(footprint ""
		(layer "B.Cu")
		(at 252.1585 -3.3528 -90)
		(property "Reference" "C5G52"
			(at -1.14681 0.76708 0)
			(unlocked yes)
			(layer "B.SilkS")
			(effects
				(font
					(size 0.7874 0.5842)
					(thickness 0.1524)
				)
				(justify mirror)
			)
		)
		(property "Value" ""
			(at 0 0 90)
			(layer "B.Fab")
			(effects
				(font
					(size 1.27 1.27)
				)
				(justify mirror)
			)
		)
		(duplicate_pad_numbers_are_jumpers no)
		(fp_rect
			(start 0.4953 1.6002)
			(end -0.4953 -0.2032)
			(stroke
				(width 0)
				(type default)
			)
			(fill no)
			(layer "B.CrtYd")
		)
		(fp_line
			(start -0.4953 1.6002)
			(end 0.4953 1.6002)
			(stroke
				(width 0.1)
				(type default)
			)
			(layer "B.Fab")
		)
		(fp_line
			(start 0.4953 1.6002)
			(end 0.4953 -0.2032)
			(stroke
				(width 0.1)
				(type default)
			)
			(layer "B.Fab")
		)
		(fp_line
			(start -0.4953 -0.2032)
			(end -0.4953 1.6002)
			(stroke
				(width 0.1)
				(type default)
			)
			(layer "B.Fab")
		)
		(fp_line
			(start 0.4953 -0.2032)
			(end -0.4953 -0.2032)
			(stroke
				(width 0.1)
				(type default)
			)
			(layer "B.Fab")
		)
		(pad "1" smd rect
			(at 0 0 90)
			(size 0.762 0.889)
			(layers "B.Cu" "B.Mask" "B.Paste")
			(net "PVDDQ_ABC")
		)
		(pad "2" smd rect
			(at 0 1.397 90)
			(size 0.762 0.889)
			(layers "B.Cu" "B.Mask" "B.Paste")
			(net "GND")
		)
		(zone
			(layer "B.Cu")
			(hatch none 0.5)
			(connect_pads
				(clearance 0)
			)
			(min_thickness 0.25)
			(keepout
				(tracks not_allowed)
				(vias allowed)
				(pads allowed)
				(copperpour not_allowed)
				(footprints allowed)
			)
			(placement
				(enabled no)
				(sheetname "")
			)
			(fill
				(thermal_gap 0.5)
				(thermal_bridge_width 0.5)
				(island_removal_mode 0)
			)
			(polygon
				(pts
					(xy 251.206 -2.9718) (xy 251.714 -2.9718) (xy 251.714 -3.7338) (xy 251.206 -3.7338)
				)
			)
		)
	)
)
